# BASEBOARD_FAB2 (Tioga Pass) — schematic netlist excerpt (pin names and nets, part order shuffled) for the footprints in the layout excerpt that follows; sources: Cadence DE-HDL packaged netlist, KiCad conversion of Wiwynn_Tioga_Pass_MB.brd

C9E6  SC22U16V5MX-4-GP  20%  pkg SMD-BCG5  page 139 : \1\ = P1V5_LAN ; \2\ = GND
C6R12  CAPP  470UF 2.5V 20% ALUM  pkg 3018  page 214 : A = PVCCIO_CPU1 ; B = GND
R4P19  RES  49.9 1% CHIP  pkg 0402  page 21 : A = H_PMSYNC_CLK_24M_CPU0 ; B = H_PMSYNC_CLK_24M

(kicad_pcb
	(version 20260206)
	(generator "pcbnew")
	(generator_version "10.0")
	(general
		(thickness 1.6)
		(legacy_teardrops no)
	)
	(paper "A4")
	(title_block
		(title "Wiwynn_Tioga_Pass_MB.brd")
		(comment 1 "Tioga Pass / footprints 4237-4239 of 4770")
	)
	(layers
		(0 "F.Cu" signal "TOP")
		(4 "In1.Cu" signal "L2GND")
		(6 "In2.Cu" signal "L3")
		(8 "In3.Cu" signal "L4GND")
		(10 "In4.Cu" signal "L5")
		(12 "In5.Cu" signal "L6GND")
		(14 "In6.Cu" signal "L7VCC")
		(16 "In7.Cu" signal "L8VCC")
		(18 "In8.Cu" signal "L9GND")
		(20 "In9.Cu" signal "L10")
		(22 "In10.Cu" signal "L11GND")
		(24 "In11.Cu" signal "L12")
		(26 "In12.Cu" signal "L13GND")
		(2 "B.Cu" signal "BOTTOM")
		(9 "F.Adhes" user "F.Adhesive")
		(11 "B.Adhes" user "B.Adhesive")
		(13 "F.Paste" user "Package Geometry/Pastemask Top")
		(15 "B.Paste" user "Package Geometry/Pastemask Bottom")
		(5 "F.SilkS" user "Ref Des/Silkscreen Top")
		(7 "B.SilkS" user "Ref Des/Silkscreen Bottom")
		(1 "F.Mask" user "Board Geometry/Soldermask Top")
		(3 "B.Mask" user "Board Geometry/Soldermask Bottom")
		(17 "Dwgs.User" user "User.Drawings")
		(19 "Cmts.User" user "User.Comments")
		(21 "Eco1.User" user "User.Eco1")
		(23 "Eco2.User" user "User.Eco2")
		(25 "Edge.Cuts" user "Board Geometry/Outline")
		(27 "Margin" user)
		(31 "F.CrtYd" user "Package Geometry/Place Bound Top")
		(29 "B.CrtYd" user "Package Geometry/Place Bound Bottom")
		(35 "F.Fab" user "Ref Des/Assembly Top")
		(33 "B.Fab" user "Ref Des/Assembly Bottom")
	)
	(footprint ""
		(layer "B.Cu")
		(at 476.48876 -43.116246 -90)
		(property "Reference" "C9E6"
			(at 0 0 90)
			(layer "B.SilkS")
			(hide yes)
			(effects
				(font
					(size 1.27 1.27)
				)
				(justify mirror)
			)
		)
		(property "Value" "*"
			(at 0.0762 -6.2357 270)
			(unlocked yes)
			(layer "B.Fab")
			(hide yes)
			(effects
				(font
					(size 1.27 1.016)
					(thickness 0.1524)
				)
				(justify mirror)
			)
		)
		(property "Device Type" "SC22U16V5MX-4-GP_SMD-BCG5-SC22A"
			(at 0.0762 -8.2677 270)
			(unlocked yes)
			(layer "B.Fab")
			(hide yes)
			(effects
				(font
					(size 1.27 1.016)
					(thickness 0.1524)
				)
				(justify mirror)
			)
		)
		(duplicate_pad_numbers_are_jumpers no)
		(fp_line
			(start -0.635 0)
			(end 0.635 0)
			(stroke
				(width 0.508)
				(type default)
			)
			(layer "B.SilkS")
		)
		(fp_rect
			(start 0.9652 1.778)
			(end -0.9652 -1.778)
			(stroke
				(width 0)
				(type default)
			)
			(fill no)
			(layer "B.CrtYd")
		)
		(fp_poly
			(pts
				(xy 0.9652 -1.778) (xy -0.9652 -1.778) (xy -0.9652 1.778) (xy 0.9652 1.778)
			)
			(stroke
				(width 0)
				(type default)
			)
			(fill no)
			(layer "B.Fab")
		)
		(pad "1" smd rect
			(at 0 -0.9652 90)
			(size 1.397 1.143)
			(layers "B.Cu" "B.Mask" "B.Paste")
			(net "P1V5_LAN")
		)
		(pad "2" smd rect
			(at 0 0.9652 90)
			(size 1.397 1.143)
			(layers "B.Cu" "B.Mask" "B.Paste")
			(net "GND")
		)
	)
	(footprint ""
		(layer "B.Cu")
		(at 164.973 -55.245 90)
		(property "Reference" "C6R12"
			(at -3.20167 4.191 0)
			(unlocked yes)
			(layer "B.SilkS")
			(effects
				(font
					(size 0.7874 0.5842)
					(thickness 0.1524)
				)
				(justify mirror)
			)
		)
		(property "Value" ""
			(at 0 0 90)
			(layer "B.Fab")
			(effects
				(font
					(size 1.27 1.27)
				)
				(justify mirror)
			)
		)
		(duplicate_pad_numbers_are_jumpers no)
		(fp_line
			(start 2.563114 -1.616456)
			(end 2.563114 1.633728)
			(stroke
				(width 0.1524)
				(type default)
			)
			(layer "B.SilkS")
		)
		(fp_line
			(start 1.6002 -1.616456)
			(end 2.563114 -1.616456)
			(stroke
				(width 0.1524)
				(type default)
			)
			(layer "B.SilkS")
		)
		(fp_line
			(start -1.6002 -1.616456)
			(end -2.504948 -1.616456)
			(stroke
				(width 0.1524)
				(type default)
			)
			(layer "B.SilkS")
		)
		(fp_line
			(start -2.504948 -1.616456)
			(end -2.504948 1.633728)
			(stroke
				(width 0.1524)
				(type default)
			)
			(layer "B.SilkS")
		)
		(fp_line
			(start 2.563114 1.633728)
			(end 1.6002 1.633728)
			(stroke
				(width 0.1524)
				(type default)
			)
			(layer "B.SilkS")
		)
		(fp_line
			(start -2.504948 1.633728)
			(end -1.6002 1.633728)
			(stroke
				(width 0.1524)
				(type default)
			)
			(layer "B.SilkS")
		)
		(fp_line
			(start 2.286 7.366)
			(end 2.286 1.632712)
			(stroke
				(width 0.1524)
				(type default)
			)
			(layer "B.SilkS")
		)
		(fp_line
			(start 2.286 7.366)
			(end 1.60147 7.366)
			(stroke
				(width 0.1524)
				(type default)
			)
			(layer "B.SilkS")
		)
		(fp_line
			(start -2.286 7.366)
			(end -2.286 1.63195)
			(stroke
				(width 0.1524)
				(type default)
			)
			(layer "B.SilkS")
		)
		(fp_line
			(start -2.286 7.366)
			(end -1.600708 7.366)
			(stroke
				(width 0.1524)
				(type default)
			)
			(layer "B.SilkS")
		)
		(fp_rect
			(start 2.286 7.366)
			(end -2.286 -0.254)
			(stroke
				(width 0)
				(type default)
			)
			(fill no)
			(layer "B.CrtYd")
		)
		(fp_line
			(start 2.286 -0.254)
			(end -2.286 -0.254)
			(stroke
				(width 0.1)
				(type default)
			)
			(layer "B.Fab")
		)
		(fp_line
			(start -2.286 -0.254)
			(end -2.286 7.366)
			(stroke
				(width 0.1)
				(type default)
			)
			(layer "B.Fab")
		)
		(fp_line
			(start 2.286 7.366)
			(end 2.286 -0.254)
			(stroke
				(width 0.1)
				(type default)
			)
			(layer "B.Fab")
		)
		(fp_line
			(start -2.286 7.366)
			(end 2.286 7.366)
			(stroke
				(width 0.1)
				(type default)
			)
			(layer "B.Fab")
		)
		(pad "1" smd rect
			(at 0 0 270)
			(size 2.54 3.048)
			(layers "B.Cu" "B.Mask" "B.Paste")
			(net "PVCCIO_CPU1")
		)
		(pad "2" smd rect
			(at 0 7.112 270)
			(size 2.54 3.048)
			(layers "B.Cu" "B.Mask" "B.Paste")
			(net "GND")
		)
	)
	(footprint ""
		(layer "B.Cu")
		(at 293.87292 -67.16268)
		(property "Reference" "R4P19"
			(at 0 0 0)
			(layer "B.SilkS")
			(hide yes)
			(effects
				(font
					(size 1.27 1.27)
				)
				(justify mirror)
			)
		)
		(property "Value" ""
			(at 0 0 0)
			(layer "B.Fab")
			(effects
				(font
					(size 1.27 1.27)
				)
				(justify mirror)
			)
		)
		(duplicate_pad_numbers_are_jumpers no)
		(fp_poly
			(pts
				(xy 0.2794 -0.1016) (xy -0.2794 -0.1016) (xy -0.2794 0.9906) (xy 0.2794 0.9906)
			)
			(stroke
				(width 0)
				(type default)
			)
			(fill no)
			(layer "B.CrtYd")
		)
		(fp_line
			(start -0.2794 -0.1016)
			(end 0.2794 -0.1016)
			(stroke
				(width 0.1)
				(type default)
			)
			(layer "B.Fab")
		)
		(fp_line
			(start -0.2794 0.9906)
			(end -0.2794 -0.1016)
			(stroke
				(width 0.1)
				(type default)
			)
			(layer "B.Fab")
		)
		(fp_line
			(start 0.2794 -0.1016)
			(end 0.2794 0.9906)
			(stroke
				(width 0.1)
				(type default)
			)
			(layer "B.Fab")
		)
		(fp_line
			(start 0.2794 0.9906)
			(end -0.2794 0.9906)
			(stroke
				(width 0.1)
				(type default)
			)
			(layer "B.Fab")
		)
		(pad "1" smd rect
			(at 0 0 180)
			(size 0.508 0.508)
			(layers "B.Cu" "B.Mask" "B.Paste")
			(net "H_PMSYNC_CLK_24M_CPU0")
		)
		(pad "2" smd rect
			(at 0 0.889 180)
			(size 0.508 0.508)
			(layers "B.Cu" "B.Mask" "B.Paste")
			(net "H_PMSYNC_CLK_24M")
		)
		(zone
			(layer "B.Cu")
			(hatch none 0.5)
			(connect_pads
				(clearance 0)
			)
			(min_thickness 0.25)
			(keepout
				(tracks allowed)
				(vias not_allowed)
				(pads allowed)
				(copperpour not_allowed)
				(footprints allowed)
			)
			(placement
				(enabled no)
				(sheetname "")
			)
			(fill
				(thermal_gap 0.5)
				(thermal_bridge_width 0.5)
				(island_removal_mode 0)
			)
			(polygon
				(pts
					(xy 294.12692 -66.90868) (xy 293.61892 -66.90868) (xy 293.61892 -66.52768) (xy 294.12692 -66.52768)
				)
			)
		)
		(zone
			(layer "B.Cu")
			(hatch none 0.5)
			(connect_pads
				(clearance 0)
			)
			(min_thickness 0.25)
			(keepout
				(tracks not_allowed)
				(vias allowed)
				(pads allowed)
				(copperpour not_allowed)
				(footprints allowed)
			)
			(placement
				(enabled no)
				(sheetname "")
			)
			(fill
				(thermal_gap 0.5)
				(thermal_bridge_width 0.5)
				(island_removal_mode 0)
			)
			(polygon
				(pts
					(xy 294.12692 -66.52768) (xy 293.61892 -66.52768) (xy 293.61892 -66.90868) (xy 294.12692 -66.90868)
				)
			)
		)
	)
)
